# S9S_MB_2U (Grand Teton) — schematic netlist excerpt (pin names and nets, part order shuffled) for the footprints in the layout excerpt that follows; sources: Cadence DE-HDL packaged netlist, KiCad conversion of 03242023_DA0F0TMBIJ0_F0T_Motherboard_J_brd_V01_OCP.brd

C1774  Q_CAP  1000PF 50V 5% EMPTY  pkg 0402  page 148 : A = FM_SWB_PWRGD_ISO ; B = GND
C830  Q_CAP_DIFFBUS  DIFF BUS_0.22UF 6.3V 20% X6S  pkg C0201  page 175 : \1\ = P5E_CPU1_PE1_TX_C_DN<3> ; \2\ = P5E_CPU1_PE1_TX_DN<3>
PC2161  Q_CAP  0.068UF 16V 10% EMPTY  pkg 0402  page 157 : A = P3V3_OCP_DVDT_1 ; B = GND

(kicad_pcb
	(version 20260206)
	(generator "pcbnew")
	(generator_version "10.0")
	(general
		(thickness 1.6)
		(legacy_teardrops no)
	)
	(paper "A4")
	(title_block
		(title "03242023_DA0F0TMBIJ0_F0T_Motherboard_J_brd_V01_OCP.brd")
		(comment 1 "Grand Teton / footprints 3820-3822 of 6105")
	)
	(layers
		(0 "F.Cu" signal "TOP")
		(4 "In1.Cu" signal "GND")
		(6 "In2.Cu" signal "IN1")
		(8 "In3.Cu" signal "GND1")
		(10 "In4.Cu" signal "IN2")
		(12 "In5.Cu" signal "GND2")
		(14 "In6.Cu" signal "IN3")
		(16 "In7.Cu" signal "GND3")
		(18 "In8.Cu" signal "VCC")
		(20 "In9.Cu" signal "VCC1")
		(22 "In10.Cu" signal "GND4")
		(24 "In11.Cu" signal "IN4")
		(26 "In12.Cu" signal "GND5")
		(28 "In13.Cu" signal "IN5")
		(30 "In14.Cu" signal "GND6")
		(32 "In15.Cu" signal "IN6")
		(34 "In16.Cu" signal "GND7")
		(2 "B.Cu" signal "BOTTOM")
		(9 "F.Adhes" user "F.Adhesive")
		(11 "B.Adhes" user "B.Adhesive")
		(13 "F.Paste" user "Package Geometry/Pastemask Top")
		(15 "B.Paste" user "Package Geometry/Pastemask Bottom")
		(5 "F.SilkS" user "Ref Des/Silkscreen Top")
		(7 "B.SilkS" user "Ref Des/Silkscreen Bottom")
		(1 "F.Mask" user "Board Geometry/Soldermask Top")
		(3 "B.Mask" user "Board Geometry/Soldermask Bottom")
		(17 "Dwgs.User" user "User.Drawings")
		(19 "Cmts.User" user "User.Comments")
		(21 "Eco1.User" user "User.Eco1")
		(23 "Eco2.User" user "User.Eco2")
		(25 "Edge.Cuts" user "Board Geometry/Outline")
		(27 "Margin" user)
		(31 "F.CrtYd" user "Package Geometry/Place Bound Top")
		(29 "B.CrtYd" user "Package Geometry/Place Bound Bottom")
		(35 "F.Fab" user "Ref Des/Assembly Top")
		(33 "B.Fab" user "Ref Des/Assembly Bottom")
	)
	(footprint ""
		(layer "F.Cu")
		(at 50.256694 -16.099536 90)
		(property "Reference" "C830"
			(at 0 0 90)
			(layer "F.SilkS")
			(hide yes)
			(effects
				(font
					(size 1.27 1.27)
				)
			)
		)
		(property "Value" ""
			(at 0 0 90)
			(layer "F.Fab")
			(effects
				(font
					(size 1.27 1.27)
				)
			)
		)
		(duplicate_pad_numbers_are_jumpers no)
		(fp_line
			(start 0.299974 -0.150114)
			(end 0.299974 0.150114)
			(stroke
				(width 0.1)
				(type default)
			)
			(layer "F.Fab")
		)
		(fp_line
			(start -0.299974 -0.150114)
			(end 0.299974 -0.150114)
			(stroke
				(width 0.1)
				(type default)
			)
			(layer "F.Fab")
		)
		(fp_line
			(start 0.299974 0.150114)
			(end -0.299974 0.150114)
			(stroke
				(width 0.1)
				(type default)
			)
			(layer "F.Fab")
		)
		(fp_line
			(start -0.299974 0.150114)
			(end -0.299974 -0.150114)
			(stroke
				(width 0.1)
				(type default)
			)
			(layer "F.Fab")
		)
		(pad "1" smd rect
			(at -0.2667 0 90)
			(size 0.3048 0.381)
			(layers "F.Cu" "F.Mask" "F.Paste")
			(net "P5E_CPU1_PE1_TX_C_DN<3>")
		)
		(pad "2" smd rect
			(at 0.2667 0 90)
			(size 0.3048 0.381)
			(layers "F.Cu" "F.Mask" "F.Paste")
			(net "P5E_CPU1_PE1_TX_DN<3>")
		)
	)
	(footprint ""
		(layer "F.Cu")
		(at 418.36594 -109.271308 90)
		(property "Reference" "PC2161"
			(at 0 0 90)
			(layer "F.SilkS")
			(hide yes)
			(effects
				(font
					(size 1.27 1.27)
				)
			)
		)
		(property "Value" ""
			(at 0 0 90)
			(layer "F.Fab")
			(effects
				(font
					(size 1.27 1.27)
				)
			)
		)
		(duplicate_pad_numbers_are_jumpers no)
		(fp_line
			(start 0.7874 -0.4064)
			(end 0.7874 0.4064)
			(stroke
				(width 0.1524)
				(type default)
			)
			(layer "F.SilkS")
		)
		(fp_line
			(start -0.7874 -0.4064)
			(end 0.7874 -0.4064)
			(stroke
				(width 0.1524)
				(type default)
			)
			(layer "F.SilkS")
		)
		(fp_line
			(start 0.7874 0.4064)
			(end -0.7874 0.4064)
			(stroke
				(width 0.1524)
				(type default)
			)
			(layer "F.SilkS")
		)
		(fp_line
			(start -0.7874 0.4064)
			(end -0.7874 -0.4064)
			(stroke
				(width 0.1524)
				(type default)
			)
			(layer "F.SilkS")
		)
		(fp_line
			(start -0.12065 -0.305054)
			(end -0.12065 -0.2794)
			(stroke
				(width 0.1)
				(type default)
			)
			(layer "F.Fab")
		)
		(fp_line
			(start -0.67945 -0.305054)
			(end -0.12065 -0.305054)
			(stroke
				(width 0.1)
				(type default)
			)
			(layer "F.Fab")
		)
		(fp_line
			(start 0.67945 -0.3048)
			(end 0.67945 0.3048)
			(stroke
				(width 0.1)
				(type default)
			)
			(layer "F.Fab")
		)
		(fp_line
			(start 0.12065 -0.3048)
			(end 0.67945 -0.3048)
			(stroke
				(width 0.1)
				(type default)
			)
			(layer "F.Fab")
		)
		(fp_line
			(start 0.12065 -0.2794)
			(end 0.12065 -0.3048)
			(stroke
				(width 0.1)
				(type default)
			)
			(layer "F.Fab")
		)
		(fp_line
			(start -0.12065 -0.2794)
			(end 0.12065 -0.2794)
			(stroke
				(width 0.1)
				(type default)
			)
			(layer "F.Fab")
		)
		(fp_line
			(start 0.120396 0.2794)
			(end -0.12065 0.2794)
			(stroke
				(width 0.1)
				(type default)
			)
			(layer "F.Fab")
		)
		(fp_line
			(start -0.12065 0.2794)
			(end -0.12065 0.3048)
			(stroke
				(width 0.1)
				(type default)
			)
			(layer "F.Fab")
		)
		(fp_line
			(start 0.67945 0.3048)
			(end 0.120396 0.3048)
			(stroke
				(width 0.1)
				(type default)
			)
			(layer "F.Fab")
		)
		(fp_line
			(start 0.120396 0.3048)
			(end 0.120396 0.2794)
			(stroke
				(width 0.1)
				(type default)
			)
			(layer "F.Fab")
		)
		(fp_line
			(start -0.12065 0.3048)
			(end -0.67945 0.3048)
			(stroke
				(width 0.1)
				(type default)
			)
			(layer "F.Fab")
		)
		(fp_line
			(start -0.67945 0.3048)
			(end -0.67945 -0.305054)
			(stroke
				(width 0.1)
				(type default)
			)
			(layer "F.Fab")
		)
		(pad "1" smd circle
			(at -0.40005 0 90)
			(size 0 0)
			(layers "F.Cu" "F.Mask" "F.Paste")
			(net "P3V3_OCP_DVDT_1")
		)
		(pad "2" smd circle
			(at 0.40005 0 90)
			(size 0 0)
			(layers "F.Cu" "F.Mask" "F.Paste")
			(net "GND")
		)
	)
	(footprint ""
		(layer "F.Cu")
		(at 424.204892 -384.266948 180)
		(property "Reference" "C1774"
			(at 0 0 180)
			(layer "F.SilkS")
			(hide yes)
			(effects
				(font
					(size 1.27 1.27)
				)
			)
		)
		(property "Value" ""
			(at 0 0 180)
			(layer "F.Fab")
			(effects
				(font
					(size 1.27 1.27)
				)
			)
		)
		(duplicate_pad_numbers_are_jumpers no)
		(fp_line
			(start 0.7874 0.4064)
			(end -0.7874 0.4064)
			(stroke
				(width 0.1524)
				(type default)
			)
			(layer "F.SilkS")
		)
		(fp_line
			(start 0.7874 -0.4064)
			(end 0.7874 0.4064)
			(stroke
				(width 0.1524)
				(type default)
			)
			(layer "F.SilkS")
		)
		(fp_line
			(start -0.7874 0.4064)
			(end -0.7874 -0.4064)
			(stroke
				(width 0.1524)
				(type default)
			)
			(layer "F.SilkS")
		)
		(fp_line
			(start -0.7874 -0.4064)
			(end 0.7874 -0.4064)
			(stroke
				(width 0.1524)
				(type default)
			)
			(layer "F.SilkS")
		)
		(fp_line
			(start 0.67945 0.3048)
			(end 0.120396 0.3048)
			(stroke
				(width 0.1)
				(type default)
			)
			(layer "F.Fab")
		)
		(fp_line
			(start 0.67945 -0.3048)
			(end 0.67945 0.3048)
			(stroke
				(width 0.1)
				(type default)
			)
			(layer "F.Fab")
		)
		(fp_line
			(start 0.12065 -0.2794)
			(end 0.12065 -0.3048)
			(stroke
				(width 0.1)
				(type default)
			)
			(layer "F.Fab")
		)
		(fp_line
			(start 0.12065 -0.3048)
			(end 0.67945 -0.3048)
			(stroke
				(width 0.1)
				(type default)
			)
			(layer "F.Fab")
		)
		(fp_line
			(start 0.120396 0.3048)
			(end 0.120396 0.2794)
			(stroke
				(width 0.1)
				(type default)
			)
			(layer "F.Fab")
		)
		(fp_line
			(start 0.120396 0.2794)
			(end -0.12065 0.2794)
			(stroke
				(width 0.1)
				(type default)
			)
			(layer "F.Fab")
		)
		(fp_line
			(start -0.12065 0.3048)
			(end -0.67945 0.3048)
			(stroke
				(width 0.1)
				(type default)
			)
			(layer "F.Fab")
		)
		(fp_line
			(start -0.12065 0.2794)
			(end -0.12065 0.3048)
			(stroke
				(width 0.1)
				(type default)
			)
			(layer "F.Fab")
		)
		(fp_line
			(start -0.12065 -0.2794)
			(end 0.12065 -0.2794)
			(stroke
				(width 0.1)
				(type default)
			)
			(layer "F.Fab")
		)
		(fp_line
			(start -0.12065 -0.305054)
			(end -0.12065 -0.2794)
			(stroke
				(width 0.1)
				(type default)
			)
			(layer "F.Fab")
		)
		(fp_line
			(start -0.67945 0.3048)
			(end -0.67945 -0.305054)
			(stroke
				(width 0.1)
				(type default)
			)
			(layer "F.Fab")
		)
		(fp_line
			(start -0.67945 -0.305054)
			(end -0.12065 -0.305054)
			(stroke
				(width 0.1)
				(type default)
			)
			(layer "F.Fab")
		)
		(pad "1" smd circle
			(at -0.40005 0 180)
			(size 0 0)
			(layers "F.Cu" "F.Mask" "F.Paste")
			(net "FM_SWB_PWRGD_ISO")
		)
		(pad "2" smd circle
			(at 0.40005 0 180)
			(size 0 0)
			(layers "F.Cu" "F.Mask" "F.Paste")
			(net "GND")
		)
	)
)
